# S9S_MB_2U (Grand Teton) — schematic netlist excerpt (pin names and nets, part order shuffled) for the footprints in the layout excerpt that follows; sources: Cadence DE-HDL packaged netlist, KiCad conversion of 03242023_DA0F0TMBIJ0_F0T_Motherboard_J_brd_V01_OCP.brd

R3287  Q_RES  1K 1% EMPTY  pkg 0402LF  page 166 : A = FM_P2E_SWB ; B = GND
PC552  Q_CAP  100NF 50V 10% EMPTY  pkg C0402  page 284 : A = PVCCIN_CPU1_VCC ; B = GND

(kicad_pcb
	(version 20260206)
	(generator "pcbnew")
	(generator_version "10.0")
	(general
		(thickness 1.6)
		(legacy_teardrops no)
	)
	(paper "A4")
	(title_block
		(title "03242023_DA0F0TMBIJ0_F0T_Motherboard_J_brd_V01_OCP.brd")
		(comment 1 "Grand Teton / footprints 996-997 of 6105")
	)
	(layers
		(0 "F.Cu" signal "TOP")
		(4 "In1.Cu" signal "GND")
		(6 "In2.Cu" signal "IN1")
		(8 "In3.Cu" signal "GND1")
		(10 "In4.Cu" signal "IN2")
		(12 "In5.Cu" signal "GND2")
		(14 "In6.Cu" signal "IN3")
		(16 "In7.Cu" signal "GND3")
		(18 "In8.Cu" signal "VCC")
		(20 "In9.Cu" signal "VCC1")
		(22 "In10.Cu" signal "GND4")
		(24 "In11.Cu" signal "IN4")
		(26 "In12.Cu" signal "GND5")
		(28 "In13.Cu" signal "IN5")
		(30 "In14.Cu" signal "GND6")
		(32 "In15.Cu" signal "IN6")
		(34 "In16.Cu" signal "GND7")
		(2 "B.Cu" signal "BOTTOM")
		(9 "F.Adhes" user "F.Adhesive")
		(11 "B.Adhes" user "B.Adhesive")
		(13 "F.Paste" user "Package Geometry/Pastemask Top")
		(15 "B.Paste" user "Package Geometry/Pastemask Bottom")
		(5 "F.SilkS" user "Ref Des/Silkscreen Top")
		(7 "B.SilkS" user "Ref Des/Silkscreen Bottom")
		(1 "F.Mask" user "Board Geometry/Soldermask Top")
		(3 "B.Mask" user "Board Geometry/Soldermask Bottom")
		(17 "Dwgs.User" user "User.Drawings")
		(19 "Cmts.User" user "User.Comments")
		(21 "Eco1.User" user "User.Eco1")
		(23 "Eco2.User" user "User.Eco2")
		(25 "Edge.Cuts" user "Board Geometry/Outline")
		(27 "Margin" user)
		(31 "F.CrtYd" user "Package Geometry/Place Bound Top")
		(29 "B.CrtYd" user "Package Geometry/Place Bound Bottom")
		(35 "F.Fab" user "Ref Des/Assembly Top")
		(33 "B.Fab" user "Ref Des/Assembly Bottom")
	)
	(footprint ""
		(layer "F.Cu")
		(at 114.706654 -362.618528)
		(property "Reference" "PC552"
			(at 0 0 0)
			(layer "F.SilkS")
			(hide yes)
			(effects
				(font
					(size 1.27 1.27)
				)
			)
		)
		(property "Value" ""
			(at 0 0 0)
			(layer "F.Fab")
			(effects
				(font
					(size 1.27 1.27)
				)
			)
		)
		(duplicate_pad_numbers_are_jumpers no)
		(fp_line
			(start -0.7874 -0.4064)
			(end 0.7874 -0.4064)
			(stroke
				(width 0.1524)
				(type default)
			)
			(layer "F.SilkS")
		)
		(fp_line
			(start -0.7874 0.4064)
			(end -0.7874 -0.4064)
			(stroke
				(width 0.1524)
				(type default)
			)
			(layer "F.SilkS")
		)
		(fp_line
			(start 0.7874 -0.4064)
			(end 0.7874 0.4064)
			(stroke
				(width 0.1524)
				(type default)
			)
			(layer "F.SilkS")
		)
		(fp_line
			(start 0.7874 0.4064)
			(end -0.7874 0.4064)
			(stroke
				(width 0.1524)
				(type default)
			)
			(layer "F.SilkS")
		)
		(fp_line
			(start -0.67945 -0.305054)
			(end -0.12065 -0.305054)
			(stroke
				(width 0.1)
				(type default)
			)
			(layer "F.Fab")
		)
		(fp_line
			(start -0.67945 0.3048)
			(end -0.67945 -0.305054)
			(stroke
				(width 0.1)
				(type default)
			)
			(layer "F.Fab")
		)
		(fp_line
			(start -0.12065 -0.305054)
			(end -0.12065 -0.2794)
			(stroke
				(width 0.1)
				(type default)
			)
			(layer "F.Fab")
		)
		(fp_line
			(start -0.12065 -0.2794)
			(end 0.12065 -0.2794)
			(stroke
				(width 0.1)
				(type default)
			)
			(layer "F.Fab")
		)
		(fp_line
			(start -0.12065 0.2794)
			(end -0.12065 0.3048)
			(stroke
				(width 0.1)
				(type default)
			)
			(layer "F.Fab")
		)
		(fp_line
			(start -0.12065 0.3048)
			(end -0.67945 0.3048)
			(stroke
				(width 0.1)
				(type default)
			)
			(layer "F.Fab")
		)
		(fp_line
			(start 0.120396 0.2794)
			(end -0.12065 0.2794)
			(stroke
				(width 0.1)
				(type default)
			)
			(layer "F.Fab")
		)
		(fp_line
			(start 0.120396 0.3048)
			(end 0.120396 0.2794)
			(stroke
				(width 0.1)
				(type default)
			)
			(layer "F.Fab")
		)
		(fp_line
			(start 0.12065 -0.3048)
			(end 0.67945 -0.3048)
			(stroke
				(width 0.1)
				(type default)
			)
			(layer "F.Fab")
		)
		(fp_line
			(start 0.12065 -0.2794)
			(end 0.12065 -0.3048)
			(stroke
				(width 0.1)
				(type default)
			)
			(layer "F.Fab")
		)
		(fp_line
			(start 0.67945 -0.3048)
			(end 0.67945 0.3048)
			(stroke
				(width 0.1)
				(type default)
			)
			(layer "F.Fab")
		)
		(fp_line
			(start 0.67945 0.3048)
			(end 0.120396 0.3048)
			(stroke
				(width 0.1)
				(type default)
			)
			(layer "F.Fab")
		)
		(pad "1" smd circle
			(at -0.40005 0)
			(size 0 0)
			(layers "F.Cu" "F.Mask" "F.Paste")
			(net "PVCCIN_CPU1_VCC")
		)
		(pad "2" smd circle
			(at 0.40005 0)
			(size 0 0)
			(layers "F.Cu" "F.Mask" "F.Paste")
			(net "GND")
		)
	)
	(footprint ""
		(layer "F.Cu")
		(at 27.628596 -391.310876)
		(property "Reference" "R3287"
			(at 0 0 0)
			(layer "F.SilkS")
			(hide yes)
			(effects
				(font
					(size 1.27 1.27)
				)
			)
		)
		(property "Value" ""
			(at 0 0 0)
			(layer "F.Fab")
			(effects
				(font
					(size 1.27 1.27)
				)
			)
		)
		(duplicate_pad_numbers_are_jumpers no)
		(fp_line
			(start -0.7874 -0.4064)
			(end 0.7874 -0.4064)
			(stroke
				(width 0.1524)
				(type default)
			)
			(layer "F.SilkS")
		)
		(fp_line
			(start -0.7874 0.4064)
			(end -0.7874 -0.4064)
			(stroke
				(width 0.1524)
				(type default)
			)
			(layer "F.SilkS")
		)
		(fp_line
			(start 0.7874 -0.4064)
			(end 0.7874 0.4064)
			(stroke
				(width 0.1524)
				(type default)
			)
			(layer "F.SilkS")
		)
		(fp_line
			(start 0.7874 0.4064)
			(end -0.7874 0.4064)
			(stroke
				(width 0.1524)
				(type default)
			)
			(layer "F.SilkS")
		)
		(fp_line
			(start -0.67945 -0.305054)
			(end -0.12065 -0.305054)
			(stroke
				(width 0.1)
				(type default)
			)
			(layer "F.Fab")
		)
		(fp_line
			(start -0.67945 0.3048)
			(end -0.67945 -0.305054)
			(stroke
				(width 0.1)
				(type default)
			)
			(layer "F.Fab")
		)
		(fp_line
			(start -0.12065 -0.305054)
			(end -0.12065 -0.2794)
			(stroke
				(width 0.1)
				(type default)
			)
			(layer "F.Fab")
		)
		(fp_line
			(start -0.12065 -0.2794)
			(end 0.12065 -0.2794)
			(stroke
				(width 0.1)
				(type default)
			)
			(layer "F.Fab")
		)
		(fp_line
			(start -0.12065 0.2794)
			(end -0.12065 0.3048)
			(stroke
				(width 0.1)
				(type default)
			)
			(layer "F.Fab")
		)
		(fp_line
			(start -0.12065 0.3048)
			(end -0.67945 0.3048)
			(stroke
				(width 0.1)
				(type default)
			)
			(layer "F.Fab")
		)
		(fp_line
			(start 0.120396 0.2794)
			(end -0.12065 0.2794)
			(stroke
				(width 0.1)
				(type default)
			)
			(layer "F.Fab")
		)
		(fp_line
			(start 0.120396 0.3048)
			(end 0.120396 0.2794)
			(stroke
				(width 0.1)
				(type default)
			)
			(layer "F.Fab")
		)
		(fp_line
			(start 0.12065 -0.3048)
			(end 0.67945 -0.3048)
			(stroke
				(width 0.1)
				(type default)
			)
			(layer "F.Fab")
		)
		(fp_line
			(start 0.12065 -0.2794)
			(end 0.12065 -0.3048)
			(stroke
				(width 0.1)
				(type default)
			)
			(layer "F.Fab")
		)
		(fp_line
			(start 0.67945 -0.3048)
			(end 0.67945 0.3048)
			(stroke
				(width 0.1)
				(type default)
			)
			(layer "F.Fab")
		)
		(fp_line
			(start 0.67945 0.3048)
			(end 0.120396 0.3048)
			(stroke
				(width 0.1)
				(type default)
			)
			(layer "F.Fab")
		)
		(pad "1" smd circle
			(at -0.40005 0)
			(size 0 0)
			(layers "F.Cu" "F.Mask" "F.Paste")
			(net "FM_P2E_SWB")
		)
		(pad "2" smd circle
			(at 0.40005 0)
			(size 0 0)
			(layers "F.Cu" "F.Mask" "F.Paste")
			(net "GND")
		)
	)
)
